# T6G (Grand Teton) — schematic netlist excerpt (pin names and nets, part order shuffled) for the footprints in the layout excerpt that follows; sources: Cadence DE-HDL packaged netlist, KiCad conversion of 04192023_DAF0TMB3IC0_F0TG_MB_C_brd_V02_OCP.brd

R3485  Q_RES  33.2 1% CHIP  pkg 0402LF  page 81 : A = GPU_WP_HW_CTRL_R_N ; B = GPU_WP_HW_CTRL_N
R285  Q_RES  33 5% CHIP  pkg 0402LF  page 82 : A = FM_PVDDCR_CPU1_P1_R_EN ; B = FM_PVDDCR_CPU1_P1_EN
R869  Q_RES  200 1% CHIP  pkg 0201LF  page 342 : A = RT_CPU1_P2_SCAN_MODE ; B = GND

(kicad_pcb
	(version 20260206)
	(generator "pcbnew")
	(generator_version "10.0")
	(general
		(thickness 1.6)
		(legacy_teardrops no)
	)
	(paper "A4")
	(title_block
		(title "04192023_DAF0TMB3IC0_F0TG_MB_C_brd_V02_OCP.brd")
		(comment 1 "Grand Teton / footprints 7466-7468 of 8354")
	)
	(layers
		(0 "F.Cu" signal "TOP")
		(4 "In1.Cu" signal "GND")
		(6 "In2.Cu" signal "IN1")
		(8 "In3.Cu" signal "GND1")
		(10 "In4.Cu" signal "IN2")
		(12 "In5.Cu" signal "GND2")
		(14 "In6.Cu" signal "IN3")
		(16 "In7.Cu" signal "GND3")
		(18 "In8.Cu" signal "VCC")
		(20 "In9.Cu" signal "VCC1")
		(22 "In10.Cu" signal "GND4")
		(24 "In11.Cu" signal "IN4")
		(26 "In12.Cu" signal "GND5")
		(28 "In13.Cu" signal "IN5")
		(30 "In14.Cu" signal "GND6")
		(32 "In15.Cu" signal "IN6")
		(34 "In16.Cu" signal "GND7")
		(2 "B.Cu" signal "BOTTOM")
		(9 "F.Adhes" user "F.Adhesive")
		(11 "B.Adhes" user "B.Adhesive")
		(13 "F.Paste" user "Package Geometry/Pastemask Top")
		(15 "B.Paste" user "Package Geometry/Pastemask Bottom")
		(5 "F.SilkS" user "Ref Des/Silkscreen Top")
		(7 "B.SilkS" user "Ref Des/Silkscreen Bottom")
		(1 "F.Mask" user "Board Geometry/Soldermask Top")
		(3 "B.Mask" user "Board Geometry/Soldermask Bottom")
		(17 "Dwgs.User" user "User.Drawings")
		(19 "Cmts.User" user "User.Comments")
		(21 "Eco1.User" user "User.Eco1")
		(23 "Eco2.User" user "User.Eco2")
		(25 "Edge.Cuts" user "Board Geometry/Outline")
		(27 "Margin" user)
		(31 "F.CrtYd" user "Package Geometry/Place Bound Top")
		(29 "B.CrtYd" user "Package Geometry/Place Bound Bottom")
		(35 "F.Fab" user "Ref Des/Assembly Top")
		(33 "B.Fab" user "Ref Des/Assembly Bottom")
	)
	(footprint ""
		(layer "B.Cu")
		(at 142.893542 -383.7432 180)
		(property "Reference" "R869"
			(at 0 0 0)
			(layer "B.SilkS")
			(hide yes)
			(effects
				(font
					(size 1.27 1.27)
				)
				(justify mirror)
			)
		)
		(property "Value" ""
			(at 0 0 0)
			(layer "B.Fab")
			(effects
				(font
					(size 1.27 1.27)
				)
				(justify mirror)
			)
		)
		(duplicate_pad_numbers_are_jumpers no)
		(fp_line
			(start 0.32512 0.175006)
			(end 0.32512 -0.175006)
			(stroke
				(width 0.1)
				(type default)
			)
			(layer "B.Fab")
		)
		(fp_line
			(start 0.32512 -0.175006)
			(end -0.32512 -0.175006)
			(stroke
				(width 0.1)
				(type default)
			)
			(layer "B.Fab")
		)
		(fp_line
			(start -0.32512 0.175006)
			(end 0.32512 0.175006)
			(stroke
				(width 0.1)
				(type default)
			)
			(layer "B.Fab")
		)
		(fp_line
			(start -0.32512 -0.175006)
			(end -0.32512 0.175006)
			(stroke
				(width 0.1)
				(type default)
			)
			(layer "B.Fab")
		)
		(pad "1" smd rect
			(at 0.2667 0)
			(size 0.3048 0.381)
			(layers "B.Cu" "B.Mask" "B.Paste")
			(net "RT_CPU1_P2_SCAN_MODE")
		)
		(pad "2" smd rect
			(at -0.2667 0 180)
			(size 0.3048 0.381)
			(layers "B.Cu" "B.Mask" "B.Paste")
			(net "GND")
		)
	)
	(footprint ""
		(layer "B.Cu")
		(at 197.269608 -107.529376 180)
		(property "Reference" "R285"
			(at 0 0 0)
			(layer "B.SilkS")
			(hide yes)
			(effects
				(font
					(size 1.27 1.27)
				)
				(justify mirror)
			)
		)
		(property "Value" ""
			(at 0 0 0)
			(layer "B.Fab")
			(effects
				(font
					(size 1.27 1.27)
				)
				(justify mirror)
			)
		)
		(duplicate_pad_numbers_are_jumpers no)
		(fp_line
			(start 0.7874 0.4064)
			(end 0.7874 -0.4064)
			(stroke
				(width 0.1524)
				(type default)
			)
			(layer "B.SilkS")
		)
		(fp_line
			(start 0.7874 -0.4064)
			(end -0.7874 -0.4064)
			(stroke
				(width 0.1524)
				(type default)
			)
			(layer "B.SilkS")
		)
		(fp_line
			(start -0.7874 0.4064)
			(end 0.7874 0.4064)
			(stroke
				(width 0.1524)
				(type default)
			)
			(layer "B.SilkS")
		)
		(fp_line
			(start -0.7874 -0.4064)
			(end -0.7874 0.4064)
			(stroke
				(width 0.1524)
				(type default)
			)
			(layer "B.SilkS")
		)
		(fp_line
			(start 0.67945 0.3048)
			(end 0.67945 -0.305054)
			(stroke
				(width 0.1)
				(type default)
			)
			(layer "B.Fab")
		)
		(fp_line
			(start 0.67945 -0.305054)
			(end 0.12065 -0.305054)
			(stroke
				(width 0.1)
				(type default)
			)
			(layer "B.Fab")
		)
		(fp_line
			(start 0.12065 0.3048)
			(end 0.67945 0.3048)
			(stroke
				(width 0.1)
				(type default)
			)
			(layer "B.Fab")
		)
		(fp_line
			(start 0.12065 0.2794)
			(end 0.12065 0.3048)
			(stroke
				(width 0.1)
				(type default)
			)
			(layer "B.Fab")
		)
		(fp_line
			(start 0.12065 -0.2794)
			(end -0.12065 -0.2794)
			(stroke
				(width 0.1)
				(type default)
			)
			(layer "B.Fab")
		)
		(fp_line
			(start 0.12065 -0.305054)
			(end 0.12065 -0.2794)
			(stroke
				(width 0.1)
				(type default)
			)
			(layer "B.Fab")
		)
		(fp_line
			(start -0.120396 0.3048)
			(end -0.120396 0.2794)
			(stroke
				(width 0.1)
				(type default)
			)
			(layer "B.Fab")
		)
		(fp_line
			(start -0.120396 0.2794)
			(end 0.12065 0.2794)
			(stroke
				(width 0.1)
				(type default)
			)
			(layer "B.Fab")
		)
		(fp_line
			(start -0.12065 -0.2794)
			(end -0.12065 -0.3048)
			(stroke
				(width 0.1)
				(type default)
			)
			(layer "B.Fab")
		)
		(fp_line
			(start -0.12065 -0.3048)
			(end -0.67945 -0.3048)
			(stroke
				(width 0.1)
				(type default)
			)
			(layer "B.Fab")
		)
		(fp_line
			(start -0.67945 0.3048)
			(end -0.120396 0.3048)
			(stroke
				(width 0.1)
				(type default)
			)
			(layer "B.Fab")
		)
		(fp_line
			(start -0.67945 -0.3048)
			(end -0.67945 0.3048)
			(stroke
				(width 0.1)
				(type default)
			)
			(layer "B.Fab")
		)
		(pad "1" smd circle
			(at 0.40005 0)
			(size 0 0)
			(layers "B.Cu" "B.Mask" "B.Paste")
			(net "FM_PVDDCR_CPU1_P1_R_EN")
		)
		(pad "2" smd circle
			(at -0.40005 0)
			(size 0 0)
			(layers "B.Cu" "B.Mask" "B.Paste")
			(net "FM_PVDDCR_CPU1_P1_EN")
		)
	)
	(footprint ""
		(layer "B.Cu")
		(at 197.955408 -122.769376 180)
		(property "Reference" "R3485"
			(at 0 0 0)
			(layer "B.SilkS")
			(hide yes)
			(effects
				(font
					(size 1.27 1.27)
				)
				(justify mirror)
			)
		)
		(property "Value" ""
			(at 0 0 0)
			(layer "B.Fab")
			(effects
				(font
					(size 1.27 1.27)
				)
				(justify mirror)
			)
		)
		(duplicate_pad_numbers_are_jumpers no)
		(fp_line
			(start 0.7874 0.4064)
			(end 0.7874 -0.4064)
			(stroke
				(width 0.1524)
				(type default)
			)
			(layer "B.SilkS")
		)
		(fp_line
			(start 0.7874 -0.4064)
			(end -0.7874 -0.4064)
			(stroke
				(width 0.1524)
				(type default)
			)
			(layer "B.SilkS")
		)
		(fp_line
			(start -0.7874 0.4064)
			(end 0.7874 0.4064)
			(stroke
				(width 0.1524)
				(type default)
			)
			(layer "B.SilkS")
		)
		(fp_line
			(start -0.7874 -0.4064)
			(end -0.7874 0.4064)
			(stroke
				(width 0.1524)
				(type default)
			)
			(layer "B.SilkS")
		)
		(fp_line
			(start 0.67945 0.3048)
			(end 0.67945 -0.305054)
			(stroke
				(width 0.1)
				(type default)
			)
			(layer "B.Fab")
		)
		(fp_line
			(start 0.67945 -0.305054)
			(end 0.12065 -0.305054)
			(stroke
				(width 0.1)
				(type default)
			)
			(layer "B.Fab")
		)
		(fp_line
			(start 0.12065 0.3048)
			(end 0.67945 0.3048)
			(stroke
				(width 0.1)
				(type default)
			)
			(layer "B.Fab")
		)
		(fp_line
			(start 0.12065 0.2794)
			(end 0.12065 0.3048)
			(stroke
				(width 0.1)
				(type default)
			)
			(layer "B.Fab")
		)
		(fp_line
			(start 0.12065 -0.2794)
			(end -0.12065 -0.2794)
			(stroke
				(width 0.1)
				(type default)
			)
			(layer "B.Fab")
		)
		(fp_line
			(start 0.12065 -0.305054)
			(end 0.12065 -0.2794)
			(stroke
				(width 0.1)
				(type default)
			)
			(layer "B.Fab")
		)
		(fp_line
			(start -0.120396 0.3048)
			(end -0.120396 0.2794)
			(stroke
				(width 0.1)
				(type default)
			)
			(layer "B.Fab")
		)
		(fp_line
			(start -0.120396 0.2794)
			(end 0.12065 0.2794)
			(stroke
				(width 0.1)
				(type default)
			)
			(layer "B.Fab")
		)
		(fp_line
			(start -0.12065 -0.2794)
			(end -0.12065 -0.3048)
			(stroke
				(width 0.1)
				(type default)
			)
			(layer "B.Fab")
		)
		(fp_line
			(start -0.12065 -0.3048)
			(end -0.67945 -0.3048)
			(stroke
				(width 0.1)
				(type default)
			)
			(layer "B.Fab")
		)
		(fp_line
			(start -0.67945 0.3048)
			(end -0.120396 0.3048)
			(stroke
				(width 0.1)
				(type default)
			)
			(layer "B.Fab")
		)
		(fp_line
			(start -0.67945 -0.3048)
			(end -0.67945 0.3048)
			(stroke
				(width 0.1)
				(type default)
			)
			(layer "B.Fab")
		)
		(pad "1" smd circle
			(at 0.40005 0)
			(size 0 0)
			(layers "B.Cu" "B.Mask" "B.Paste")
			(net "GPU_WP_HW_CTRL_R_N")
		)
		(pad "2" smd circle
			(at -0.40005 0)
			(size 0 0)
			(layers "B.Cu" "B.Mask" "B.Paste")
			(net "GPU_WP_HW_CTRL_N")
		)
	)
)
